FILE_TYPE=LIBRARY_PARTS;
primitive 'MAX9634','MAX9634_SOT';
  pin
    'GND'<1>:
      PIN_NUMBER='(1)';
      PINUSE='GROUND';
      NO_LOAD_CHECK='Both';
      NO_IO_CHECK='Both';
      NO_ASSERT_CHECK='TRUE';
      NO_DIR_CHECK='TRUE';
      ALLOW_CONNECT='TRUE';
    'GND'<0>:
      PIN_NUMBER='(2)';
      PINUSE='GROUND';
      NO_LOAD_CHECK='Both';
      NO_IO_CHECK='Both';
      NO_ASSERT_CHECK='TRUE';
      NO_DIR_CHECK='TRUE';
      ALLOW_CONNECT='TRUE';
    'OUT':
      PIN_NUMBER='(3)';
      OUTPUT_LOAD='(1.0,-1.0)';
    'RSN':
      PIN_NUMBER='(4)';
      INPUT_LOAD='(-0.01,0.01)';
    'RSP':
      PIN_NUMBER='(5)';
      INPUT_LOAD='(-0.01,0.01)';
  end_pin;
  body
    PART_NAME='MAX9634';
    PHYS_DES_PREFIX='U';
  end_body;
end_primitive;

END.
